# BASEBOARD_FAB2 (Tioga Pass) — schematic netlist excerpt (pin names and nets, part order shuffled) for the footprints in the layout excerpt that follows; sources: Cadence DE-HDL packaged netlist, KiCad conversion of Wiwynn_Tioga_Pass_MB.brd

Q7E8  FET_N  2N7002 FET  pkg SOT23LF  page 95
  GATE  = FM_SYS_THROTTLE_LVC3
  SRC  = GND
  DRN  = FM_PWRBRK_N

R5R1  RES  49.9 1% CHIP  pkg 0402  page 22 : A = PD_CPU0_RSVD_TEST_1 ; B = GND
C9N7  CAP  0.22UF 16V 10% X7R  pkg 0402  page 182 : A = P3E_CPU1_PE3_MP_C_TXP<15> ; B = P3E_CPU1_PE3_MP_TXP<15>

(kicad_pcb
	(version 20260206)
	(generator "pcbnew")
	(generator_version "10.0")
	(general
		(thickness 1.6)
		(legacy_teardrops no)
	)
	(paper "A4")
	(title_block
		(title "Wiwynn_Tioga_Pass_MB.brd")
		(comment 1 "Tioga Pass / footprints 3150-3152 of 4770")
	)
	(layers
		(0 "F.Cu" signal "TOP")
		(4 "In1.Cu" signal "L2GND")
		(6 "In2.Cu" signal "L3")
		(8 "In3.Cu" signal "L4GND")
		(10 "In4.Cu" signal "L5")
		(12 "In5.Cu" signal "L6GND")
		(14 "In6.Cu" signal "L7VCC")
		(16 "In7.Cu" signal "L8VCC")
		(18 "In8.Cu" signal "L9GND")
		(20 "In9.Cu" signal "L10")
		(22 "In10.Cu" signal "L11GND")
		(24 "In11.Cu" signal "L12")
		(26 "In12.Cu" signal "L13GND")
		(2 "B.Cu" signal "BOTTOM")
		(9 "F.Adhes" user "F.Adhesive")
		(11 "B.Adhes" user "B.Adhesive")
		(13 "F.Paste" user "Package Geometry/Pastemask Top")
		(15 "B.Paste" user "Package Geometry/Pastemask Bottom")
		(5 "F.SilkS" user "Ref Des/Silkscreen Top")
		(7 "B.SilkS" user "Ref Des/Silkscreen Bottom")
		(1 "F.Mask" user "Board Geometry/Soldermask Top")
		(3 "B.Mask" user "Board Geometry/Soldermask Bottom")
		(17 "Dwgs.User" user "User.Drawings")
		(19 "Cmts.User" user "User.Comments")
		(21 "Eco1.User" user "User.Eco1")
		(23 "Eco2.User" user "User.Eco2")
		(25 "Edge.Cuts" user "Board Geometry/Outline")
		(27 "Margin" user)
		(31 "F.CrtYd" user "Package Geometry/Place Bound Top")
		(29 "B.CrtYd" user "Package Geometry/Place Bound Bottom")
		(35 "F.Fab" user "Ref Des/Assembly Top")
		(33 "B.Fab" user "Ref Des/Assembly Bottom")
	)
	(footprint ""
		(layer "B.Cu")
		(at 380.3904 -43.7515)
		(property "Reference" "Q7E8"
			(at 1.28143 0.59944 90)
			(unlocked yes)
			(layer "B.SilkS")
			(effects
				(font
					(size 0.7874 0.5842)
					(thickness 0.1524)
				)
				(justify left mirror)
			)
		)
		(property "Value" ""
			(at 0 0 0)
			(layer "B.Fab")
			(effects
				(font
					(size 1.27 1.27)
				)
				(justify mirror)
			)
		)
		(duplicate_pad_numbers_are_jumpers no)
		(fp_line
			(start -1.778 -0.5715)
			(end -1.778 0.3175)
			(stroke
				(width 0.1524)
				(type default)
			)
			(layer "B.SilkS")
		)
		(fp_line
			(start -1.778 2.4765)
			(end -1.778 1.5875)
			(stroke
				(width 0.1524)
				(type default)
			)
			(layer "B.SilkS")
		)
		(fp_line
			(start -0.9525 -0.5715)
			(end -1.778 -0.5715)
			(stroke
				(width 0.1524)
				(type default)
			)
			(layer "B.SilkS")
		)
		(fp_line
			(start -0.9525 2.4765)
			(end -1.778 2.4765)
			(stroke
				(width 0.1524)
				(type default)
			)
			(layer "B.SilkS")
		)
		(fp_line
			(start -0.381 0.635)
			(end -0.381 1.27)
			(stroke
				(width 0.1524)
				(type default)
			)
			(layer "B.SilkS")
		)
		(fp_circle
			(center 0.9525 -0.9271)
			(end 1.0795 -0.9271)
			(stroke
				(width 0.254)
				(type default)
			)
			(fill no)
			(layer "B.SilkS")
		)
		(fp_poly
			(pts
				(xy -1.778 2.4765) (xy -0.381 2.4765) (xy -0.381 -0.5715) (xy -1.778 -0.5715)
			)
			(stroke
				(width 0)
				(type default)
			)
			(fill no)
			(layer "B.CrtYd")
		)
		(fp_line
			(start -1.778 -0.5715)
			(end -0.381 -0.5715)
			(stroke
				(width 0.1)
				(type default)
			)
			(layer "B.Fab")
		)
		(fp_line
			(start -1.778 2.4765)
			(end -1.778 -0.5715)
			(stroke
				(width 0.1)
				(type default)
			)
			(layer "B.Fab")
		)
		(fp_line
			(start -0.381 -0.5715)
			(end -0.381 2.4765)
			(stroke
				(width 0.1)
				(type default)
			)
			(layer "B.Fab")
		)
		(fp_line
			(start -0.381 2.4765)
			(end -1.778 2.4765)
			(stroke
				(width 0.1)
				(type default)
			)
			(layer "B.Fab")
		)
		(fp_circle
			(center 0.9525 -0.9271)
			(end 1.0795 -0.9271)
			(stroke
				(width 0.254)
				(type default)
			)
			(fill no)
			(layer "B.Fab")
		)
		(pad "1" smd rect
			(at 0 0 180)
			(size 1.143 0.508)
			(layers "B.Cu" "B.Mask" "B.Paste")
			(net "FM_SYS_THROTTLE_LVC3")
		)
		(pad "2" smd rect
			(at 0 1.905 180)
			(size 1.143 0.508)
			(layers "B.Cu" "B.Mask" "B.Paste")
			(net "GND")
		)
		(pad "3" smd rect
			(at -2.159 0.9525 180)
			(size 1.143 0.508)
			(layers "B.Cu" "B.Mask" "B.Paste")
			(net "FM_PWRBRK_N")
		)
	)
	(footprint ""
		(layer "B.Cu")
		(at 17.83842 -103.34752 90)
		(property "Reference" "C9N7"
			(at 0 0 90)
			(layer "B.SilkS")
			(hide yes)
			(effects
				(font
					(size 1.27 1.27)
				)
				(justify mirror)
			)
		)
		(property "Value" ""
			(at 0 0 90)
			(layer "B.Fab")
			(effects
				(font
					(size 1.27 1.27)
				)
				(justify mirror)
			)
		)
		(duplicate_pad_numbers_are_jumpers no)
		(fp_poly
			(pts
				(xy -0.3048 -0.1016) (xy -0.3048 0.9906) (xy 0.3048 0.9906) (xy 0.3048 -0.1016)
			)
			(stroke
				(width 0)
				(type default)
			)
			(fill no)
			(layer "B.CrtYd")
		)
		(fp_line
			(start 0.3048 -0.1016)
			(end 0.3048 0.9906)
			(stroke
				(width 0.1)
				(type default)
			)
			(layer "B.Fab")
		)
		(fp_line
			(start -0.3048 -0.1016)
			(end 0.3048 -0.1016)
			(stroke
				(width 0.1)
				(type default)
			)
			(layer "B.Fab")
		)
		(fp_line
			(start 0.3048 0.9906)
			(end -0.3048 0.9906)
			(stroke
				(width 0.1)
				(type default)
			)
			(layer "B.Fab")
		)
		(fp_line
			(start -0.3048 0.9906)
			(end -0.3048 -0.1016)
			(stroke
				(width 0.1)
				(type default)
			)
			(layer "B.Fab")
		)
		(pad "1" smd rect
			(at 0 0 270)
			(size 0.508 0.508)
			(layers "B.Cu" "B.Mask" "B.Paste")
			(net "P3E_CPU1_PE3_MP_C_TXP<15>")
		)
		(pad "2" smd rect
			(at 0 0.889 270)
			(size 0.508 0.508)
			(layers "B.Cu" "B.Mask" "B.Paste")
			(net "P3E_CPU1_PE3_MP_TXP<15>")
		)
		(zone
			(layer "B.Cu")
			(hatch none 0.5)
			(connect_pads
				(clearance 0)
			)
			(min_thickness 0.25)
			(keepout
				(tracks allowed)
				(vias not_allowed)
				(pads allowed)
				(copperpour not_allowed)
				(footprints allowed)
			)
			(placement
				(enabled no)
				(sheetname "")
			)
			(fill
				(thermal_gap 0.5)
				(thermal_bridge_width 0.5)
				(island_removal_mode 0)
			)
			(polygon
				(pts
					(xy 18.09242 -103.60152) (xy 18.09242 -103.09352) (xy 18.47342 -103.09352) (xy 18.47342 -103.60152)
				)
			)
		)
		(zone
			(layer "B.Cu")
			(hatch none 0.5)
			(connect_pads
				(clearance 0)
			)
			(min_thickness 0.25)
			(keepout
				(tracks not_allowed)
				(vias allowed)
				(pads allowed)
				(copperpour not_allowed)
				(footprints allowed)
			)
			(placement
				(enabled no)
				(sheetname "")
			)
			(fill
				(thermal_gap 0.5)
				(thermal_bridge_width 0.5)
				(island_removal_mode 0)
			)
			(polygon
				(pts
					(xy 18.47342 -103.60152) (xy 18.47342 -103.09352) (xy 18.09242 -103.09352) (xy 18.09242 -103.60152)
				)
			)
		)
	)
	(footprint ""
		(layer "B.Cu")
		(at 245.018306 -64.2874 -90)
		(property "Reference" "R5R1"
			(at 0 0 90)
			(layer "B.SilkS")
			(hide yes)
			(effects
				(font
					(size 1.27 1.27)
				)
				(justify mirror)
			)
		)
		(property "Value" ""
			(at 0 0 90)
			(layer "B.Fab")
			(effects
				(font
					(size 1.27 1.27)
				)
				(justify mirror)
			)
		)
		(duplicate_pad_numbers_are_jumpers no)
		(fp_poly
			(pts
				(xy 0.2794 -0.1016) (xy -0.2794 -0.1016) (xy -0.2794 0.9906) (xy 0.2794 0.9906)
			)
			(stroke
				(width 0)
				(type default)
			)
			(fill no)
			(layer "B.CrtYd")
		)
		(fp_line
			(start -0.2794 0.9906)
			(end -0.2794 -0.1016)
			(stroke
				(width 0.1)
				(type default)
			)
			(layer "B.Fab")
		)
		(fp_line
			(start 0.2794 0.9906)
			(end -0.2794 0.9906)
			(stroke
				(width 0.1)
				(type default)
			)
			(layer "B.Fab")
		)
		(fp_line
			(start -0.2794 -0.1016)
			(end 0.2794 -0.1016)
			(stroke
				(width 0.1)
				(type default)
			)
			(layer "B.Fab")
		)
		(fp_line
			(start 0.2794 -0.1016)
			(end 0.2794 0.9906)
			(stroke
				(width 0.1)
				(type default)
			)
			(layer "B.Fab")
		)
		(pad "1" smd rect
			(at 0 0 90)
			(size 0.508 0.508)
			(layers "B.Cu" "B.Mask" "B.Paste")
			(net "PD_CPU0_RSVD_TEST_1")
		)
		(pad "2" smd rect
			(at 0 0.889 90)
			(size 0.508 0.508)
			(layers "B.Cu" "B.Mask" "B.Paste")
			(net "GND")
		)
		(zone
			(layer "B.Cu")
			(hatch none 0.5)
			(connect_pads
				(clearance 0)
			)
			(min_thickness 0.25)
			(keepout
				(tracks not_allowed)
				(vias allowed)
				(pads allowed)
				(copperpour not_allowed)
				(footprints allowed)
			)
			(placement
				(enabled no)
				(sheetname "")
			)
			(fill
				(thermal_gap 0.5)
				(thermal_bridge_width 0.5)
				(island_removal_mode 0)
			)
			(polygon
				(pts
					(xy 244.383306 -64.0334) (xy 244.383306 -64.5414) (xy 244.764306 -64.5414) (xy 244.764306 -64.0334)
				)
			)
		)
		(zone
			(layer "B.Cu")
			(hatch none 0.5)
			(connect_pads
				(clearance 0)
			)
			(min_thickness 0.25)
			(keepout
				(tracks allowed)
				(vias not_allowed)
				(pads allowed)
				(copperpour not_allowed)
				(footprints allowed)
			)
			(placement
				(enabled no)
				(sheetname "")
			)
			(fill
				(thermal_gap 0.5)
				(thermal_bridge_width 0.5)
				(island_removal_mode 0)
			)
			(polygon
				(pts
					(xy 244.764306 -64.0334) (xy 244.764306 -64.5414) (xy 244.383306 -64.5414) (xy 244.383306 -64.0334)
				)
			)
		)
	)
)
